# T6G (Grand Teton) — schematic netlist excerpt (pin names and nets, part order shuffled) for the footprints in the layout excerpt that follows; sources: Cadence DE-HDL packaged netlist, KiCad conversion of 04192023_DAF0TMB3IC0_F0TG_MB_C_brd_V02_OCP.brd

C6562  Q_CAP_DIFFBUS  DIFF BUS_0.22UF 6.3V 20% X6S  pkg C0201  page 286 : \1\ = P5E_CPU0_P1_TX_BUF_C_DN<14> ; \2\ = P5E_CPU0_P1_TX_BUF_DN<14>
R306  Q_RES  1K 1% CHIP  pkg 0402LF  page 101 : A = PWRGD_CHD_CPU1_DIMM ; B = PWRGD_CHAF_CPU1
R433  Q_RES  20M 1% CHIP  pkg 0402LF  page 28 : A = XTAL_CPU0_X32K_X1 ; B = XTAL_CPU0_X32K_X2

(kicad_pcb
	(version 20260206)
	(generator "pcbnew")
	(generator_version "10.0")
	(general
		(thickness 1.6)
		(legacy_teardrops no)
	)
	(paper "A4")
	(title_block
		(title "04192023_DAF0TMB3IC0_F0TG_MB_C_brd_V02_OCP.brd")
		(comment 1 "Grand Teton / footprints 6638-6640 of 8354")
	)
	(layers
		(0 "F.Cu" signal "TOP")
		(4 "In1.Cu" signal "GND")
		(6 "In2.Cu" signal "IN1")
		(8 "In3.Cu" signal "GND1")
		(10 "In4.Cu" signal "IN2")
		(12 "In5.Cu" signal "GND2")
		(14 "In6.Cu" signal "IN3")
		(16 "In7.Cu" signal "GND3")
		(18 "In8.Cu" signal "VCC")
		(20 "In9.Cu" signal "VCC1")
		(22 "In10.Cu" signal "GND4")
		(24 "In11.Cu" signal "IN4")
		(26 "In12.Cu" signal "GND5")
		(28 "In13.Cu" signal "IN5")
		(30 "In14.Cu" signal "GND6")
		(32 "In15.Cu" signal "IN6")
		(34 "In16.Cu" signal "GND7")
		(2 "B.Cu" signal "BOTTOM")
		(9 "F.Adhes" user "F.Adhesive")
		(11 "B.Adhes" user "B.Adhesive")
		(13 "F.Paste" user "Package Geometry/Pastemask Top")
		(15 "B.Paste" user "Package Geometry/Pastemask Bottom")
		(5 "F.SilkS" user "Ref Des/Silkscreen Top")
		(7 "B.SilkS" user "Ref Des/Silkscreen Bottom")
		(1 "F.Mask" user "Board Geometry/Soldermask Top")
		(3 "B.Mask" user "Board Geometry/Soldermask Bottom")
		(17 "Dwgs.User" user "User.Drawings")
		(19 "Cmts.User" user "User.Comments")
		(21 "Eco1.User" user "User.Eco1")
		(23 "Eco2.User" user "User.Eco2")
		(25 "Edge.Cuts" user "Board Geometry/Outline")
		(27 "Margin" user)
		(31 "F.CrtYd" user "Package Geometry/Place Bound Top")
		(29 "B.CrtYd" user "Package Geometry/Place Bound Bottom")
		(35 "F.Fab" user "Ref Des/Assembly Top")
		(33 "B.Fab" user "Ref Des/Assembly Bottom")
	)
	(footprint ""
		(layer "B.Cu")
		(at 348.185486 -416.899344 90)
		(property "Reference" "C6562"
			(at 0 0 90)
			(layer "B.SilkS")
			(hide yes)
			(effects
				(font
					(size 1.27 1.27)
				)
				(justify mirror)
			)
		)
		(property "Value" ""
			(at 0 0 90)
			(layer "B.Fab")
			(effects
				(font
					(size 1.27 1.27)
				)
				(justify mirror)
			)
		)
		(duplicate_pad_numbers_are_jumpers no)
		(fp_line
			(start 0.299974 -0.150114)
			(end -0.299974 -0.150114)
			(stroke
				(width 0.1)
				(type default)
			)
			(layer "B.Fab")
		)
		(fp_line
			(start -0.299974 -0.150114)
			(end -0.299974 0.150114)
			(stroke
				(width 0.1)
				(type default)
			)
			(layer "B.Fab")
		)
		(fp_line
			(start 0.299974 0.150114)
			(end 0.299974 -0.150114)
			(stroke
				(width 0.1)
				(type default)
			)
			(layer "B.Fab")
		)
		(fp_line
			(start -0.299974 0.150114)
			(end 0.299974 0.150114)
			(stroke
				(width 0.1)
				(type default)
			)
			(layer "B.Fab")
		)
		(pad "1" smd rect
			(at 0.2667 0 270)
			(size 0.3048 0.381)
			(layers "B.Cu" "B.Mask" "B.Paste")
			(net "P5E_CPU0_P1_TX_BUF_C_DN<14>")
		)
		(pad "2" smd rect
			(at -0.2667 0 270)
			(size 0.3048 0.381)
			(layers "B.Cu" "B.Mask" "B.Paste")
			(net "P5E_CPU0_P1_TX_BUF_DN<14>")
		)
	)
	(footprint ""
		(layer "B.Cu")
		(at 400.761962 -313.782964 180)
		(property "Reference" "R433"
			(at 0 0 0)
			(layer "B.SilkS")
			(hide yes)
			(effects
				(font
					(size 1.27 1.27)
				)
				(justify mirror)
			)
		)
		(property "Value" ""
			(at 0 0 0)
			(layer "B.Fab")
			(effects
				(font
					(size 1.27 1.27)
				)
				(justify mirror)
			)
		)
		(duplicate_pad_numbers_are_jumpers no)
		(fp_line
			(start 0.7874 0.4064)
			(end 0.7874 -0.4064)
			(stroke
				(width 0.1524)
				(type default)
			)
			(layer "B.SilkS")
		)
		(fp_line
			(start 0.7874 -0.4064)
			(end -0.7874 -0.4064)
			(stroke
				(width 0.1524)
				(type default)
			)
			(layer "B.SilkS")
		)
		(fp_line
			(start -0.7874 0.4064)
			(end 0.7874 0.4064)
			(stroke
				(width 0.1524)
				(type default)
			)
			(layer "B.SilkS")
		)
		(fp_line
			(start -0.7874 -0.4064)
			(end -0.7874 0.4064)
			(stroke
				(width 0.1524)
				(type default)
			)
			(layer "B.SilkS")
		)
		(fp_line
			(start 0.67945 0.3048)
			(end 0.67945 -0.305054)
			(stroke
				(width 0.1)
				(type default)
			)
			(layer "B.Fab")
		)
		(fp_line
			(start 0.67945 -0.305054)
			(end 0.12065 -0.305054)
			(stroke
				(width 0.1)
				(type default)
			)
			(layer "B.Fab")
		)
		(fp_line
			(start 0.12065 0.3048)
			(end 0.67945 0.3048)
			(stroke
				(width 0.1)
				(type default)
			)
			(layer "B.Fab")
		)
		(fp_line
			(start 0.12065 0.2794)
			(end 0.12065 0.3048)
			(stroke
				(width 0.1)
				(type default)
			)
			(layer "B.Fab")
		)
		(fp_line
			(start 0.12065 -0.2794)
			(end -0.12065 -0.2794)
			(stroke
				(width 0.1)
				(type default)
			)
			(layer "B.Fab")
		)
		(fp_line
			(start 0.12065 -0.305054)
			(end 0.12065 -0.2794)
			(stroke
				(width 0.1)
				(type default)
			)
			(layer "B.Fab")
		)
		(fp_line
			(start -0.120396 0.3048)
			(end -0.120396 0.2794)
			(stroke
				(width 0.1)
				(type default)
			)
			(layer "B.Fab")
		)
		(fp_line
			(start -0.120396 0.2794)
			(end 0.12065 0.2794)
			(stroke
				(width 0.1)
				(type default)
			)
			(layer "B.Fab")
		)
		(fp_line
			(start -0.12065 -0.2794)
			(end -0.12065 -0.3048)
			(stroke
				(width 0.1)
				(type default)
			)
			(layer "B.Fab")
		)
		(fp_line
			(start -0.12065 -0.3048)
			(end -0.67945 -0.3048)
			(stroke
				(width 0.1)
				(type default)
			)
			(layer "B.Fab")
		)
		(fp_line
			(start -0.67945 0.3048)
			(end -0.120396 0.3048)
			(stroke
				(width 0.1)
				(type default)
			)
			(layer "B.Fab")
		)
		(fp_line
			(start -0.67945 -0.3048)
			(end -0.67945 0.3048)
			(stroke
				(width 0.1)
				(type default)
			)
			(layer "B.Fab")
		)
		(pad "1" smd circle
			(at 0.40005 0)
			(size 0 0)
			(layers "B.Cu" "B.Mask" "B.Paste")
			(net "XTAL_CPU0_X32K_X1")
		)
		(pad "2" smd circle
			(at -0.40005 0)
			(size 0 0)
			(layers "B.Cu" "B.Mask" "B.Paste")
			(net "XTAL_CPU0_X32K_X2")
		)
	)
	(footprint ""
		(layer "B.Cu")
		(at 32.552386 -190.948564 180)
		(property "Reference" "R306"
			(at 0 0 0)
			(layer "B.SilkS")
			(hide yes)
			(effects
				(font
					(size 1.27 1.27)
				)
				(justify mirror)
			)
		)
		(property "Value" ""
			(at 0 0 0)
			(layer "B.Fab")
			(effects
				(font
					(size 1.27 1.27)
				)
				(justify mirror)
			)
		)
		(duplicate_pad_numbers_are_jumpers no)
		(fp_line
			(start 0.7874 0.4064)
			(end 0.7874 -0.4064)
			(stroke
				(width 0.1524)
				(type default)
			)
			(layer "B.SilkS")
		)
		(fp_line
			(start 0.7874 -0.4064)
			(end -0.7874 -0.4064)
			(stroke
				(width 0.1524)
				(type default)
			)
			(layer "B.SilkS")
		)
		(fp_line
			(start -0.7874 0.4064)
			(end 0.7874 0.4064)
			(stroke
				(width 0.1524)
				(type default)
			)
			(layer "B.SilkS")
		)
		(fp_line
			(start -0.7874 -0.4064)
			(end -0.7874 0.4064)
			(stroke
				(width 0.1524)
				(type default)
			)
			(layer "B.SilkS")
		)
		(fp_line
			(start 0.67945 0.3048)
			(end 0.67945 -0.305054)
			(stroke
				(width 0.1)
				(type default)
			)
			(layer "B.Fab")
		)
		(fp_line
			(start 0.67945 -0.305054)
			(end 0.12065 -0.305054)
			(stroke
				(width 0.1)
				(type default)
			)
			(layer "B.Fab")
		)
		(fp_line
			(start 0.12065 0.3048)
			(end 0.67945 0.3048)
			(stroke
				(width 0.1)
				(type default)
			)
			(layer "B.Fab")
		)
		(fp_line
			(start 0.12065 0.2794)
			(end 0.12065 0.3048)
			(stroke
				(width 0.1)
				(type default)
			)
			(layer "B.Fab")
		)
		(fp_line
			(start 0.12065 -0.2794)
			(end -0.12065 -0.2794)
			(stroke
				(width 0.1)
				(type default)
			)
			(layer "B.Fab")
		)
		(fp_line
			(start 0.12065 -0.305054)
			(end 0.12065 -0.2794)
			(stroke
				(width 0.1)
				(type default)
			)
			(layer "B.Fab")
		)
		(fp_line
			(start -0.120396 0.3048)
			(end -0.120396 0.2794)
			(stroke
				(width 0.1)
				(type default)
			)
			(layer "B.Fab")
		)
		(fp_line
			(start -0.120396 0.2794)
			(end 0.12065 0.2794)
			(stroke
				(width 0.1)
				(type default)
			)
			(layer "B.Fab")
		)
		(fp_line
			(start -0.12065 -0.2794)
			(end -0.12065 -0.3048)
			(stroke
				(width 0.1)
				(type default)
			)
			(layer "B.Fab")
		)
		(fp_line
			(start -0.12065 -0.3048)
			(end -0.67945 -0.3048)
			(stroke
				(width 0.1)
				(type default)
			)
			(layer "B.Fab")
		)
		(fp_line
			(start -0.67945 0.3048)
			(end -0.120396 0.3048)
			(stroke
				(width 0.1)
				(type default)
			)
			(layer "B.Fab")
		)
		(fp_line
			(start -0.67945 -0.3048)
			(end -0.67945 0.3048)
			(stroke
				(width 0.1)
				(type default)
			)
			(layer "B.Fab")
		)
		(pad "1" smd circle
			(at 0.40005 0)
			(size 0 0)
			(layers "B.Cu" "B.Mask" "B.Paste")
			(net "PWRGD_CHD_CPU1_DIMM")
		)
		(pad "2" smd circle
			(at -0.40005 0)
			(size 0 0)
			(layers "B.Cu" "B.Mask" "B.Paste")
			(net "PWRGD_CHAF_CPU1")
		)
	)
)
